G04 ================== begin FILE IDENTIFICATION RECORD ==================*
G04 Layout Name:  13919-sa.brd*
G04 Film Name:    WSILK_T*
G04 File Format:  Gerber RS274X*
G04 File Origin:  Cadence Allegro 16.5-S039*
G04 Origin Date:  Fri Nov 22 15:27:03 2013*
G04 *
G04 Layer:  DRAWING FORMAT/LAYER_WSILK_T*
G04 Layer:  DRAWING FORMAT/LAYER_PCB_STORY*
G04 Layer:  BOARD GEOMETRY/WSILK_T*
G04 Layer:  BOARD GEOMETRY/PANEL_OUTLINE*
G04 *
G04 Offset:    (0.00 0.00)*
G04 Mirror:    No*
G04 Mode:      Positive*
G04 Rotation:  0*
G04 FullContactRelief:  No*
G04 UndefLineWidth:     6.00*
G04 ================== end FILE IDENTIFICATION RECORD ====================*
%FSLAX35Y35*MOIN*%
%IR0*IPPOS*OFA0.00000B0.00000*MIA0B0*SFA1.00000B1.00000*%
%ADD10C,.02*%
%ADD11C,.006*%
G75*
%LPD*%
G75*
G54D10*
G01X-67189Y-77263D02*
G02I-12000J0D01*
G01X-72339D02*
G02I-6850J0D01*
G01X-79189Y-93263D02*
Y-61263D01*
G01X-63189Y-77263D02*
X-95189D01*
G01X-63189Y-93263D02*
Y-173263D01*
G01D02*
X1156611D01*
G01X-63189Y-93263D02*
X1156611D01*
G01X-63189Y-128763D02*
X1156611D01*
G01X369111Y-93263D02*
Y-173263D01*
G01X506611Y-93263D02*
Y-173263D01*
G01X621611Y-93263D02*
Y-173263D01*
G01X789111Y-93263D02*
Y-173263D01*
G01X959111Y-93263D02*
Y-173263D01*
G01X1156611Y-93263D02*
Y-173263D01*
G01X1184611Y-77263D02*
G02I-12000J0D01*
G01X1179461D02*
G02I-6850J0D01*
G01X1172611Y-93263D02*
Y-61263D01*
G01X1188611Y-77263D02*
X1156611D01*
G54D11*
G01X-44374Y-163263D02*
Y-145763D01*
G01X-35204D02*
Y-163263D01*
G01Y-154513D02*
X-44374D01*
G01X-22289Y-163263D02*
X-23599Y-162971D01*
X-24909Y-161805D01*
X-25783Y-159763D01*
X-26219Y-157430D01*
X-25783Y-155096D01*
X-24909Y-153055D01*
X-23599Y-151888D01*
X-22289Y-151597D01*
X-20979Y-151888D01*
X-19669Y-153055D01*
X-18796Y-155096D01*
X-18577Y-157430D01*
X-18796Y-159763D01*
X-19669Y-161805D01*
X-20979Y-162971D01*
X-22289Y-163263D01*
G01X-8501D02*
Y-151597D01*
G01Y-154513D02*
X-7627Y-153055D01*
X-6317Y-151888D01*
X-4571Y-151597D01*
X-3043Y-151888D01*
X-1732Y-153055D01*
X-1077Y-155096D01*
Y-163263D01*
G01X9436Y-155388D02*
X16423D01*
X15768Y-153346D01*
X14676Y-152180D01*
X13148Y-151597D01*
X11619Y-151888D01*
X10309Y-152763D01*
X9436Y-154805D01*
X8999Y-156555D01*
Y-158305D01*
X9436Y-160055D01*
X10528Y-161805D01*
X11838Y-162971D01*
X13366Y-163263D01*
X14894Y-162680D01*
X16423Y-160930D01*
G01X25626Y-168513D02*
X26936Y-169096D01*
X28683Y-168513D01*
X29774Y-167347D01*
X30648Y-165888D01*
X31957Y-161222D01*
X34796Y-151597D01*
G01X27809D02*
X31957Y-161222D01*
G01X66957Y-153930D02*
X67831Y-153055D01*
X68486Y-151597D01*
X68923Y-149554D01*
X68486Y-147805D01*
X67613Y-146638D01*
X66084Y-145763D01*
X60189D01*
Y-163263D01*
X67394D01*
X68923Y-162097D01*
X69796Y-160346D01*
X70233Y-158305D01*
X69796Y-156263D01*
X68486Y-154513D01*
X66957Y-153930D01*
X60189D01*
G01X86641Y-163263D02*
Y-151597D01*
G01Y-153638D02*
X85768Y-152472D01*
X84457Y-151888D01*
X82929Y-151597D01*
X81401Y-152180D01*
X80091Y-153346D01*
X79217Y-155096D01*
X78781Y-157430D01*
X79217Y-159763D01*
X80091Y-161513D01*
X81401Y-162680D01*
X82929Y-163263D01*
X84457Y-162971D01*
X85768Y-162097D01*
X86641Y-160930D01*
G01X104141Y-145763D02*
Y-163263D01*
G01Y-160639D02*
X103268Y-162097D01*
X101957Y-162971D01*
X100429Y-163263D01*
X98683Y-162680D01*
X97373Y-161222D01*
X96499Y-159472D01*
X96281Y-157430D01*
X96499Y-155388D01*
X97373Y-153638D01*
X98683Y-152180D01*
X100429Y-151597D01*
X101957Y-151888D01*
X103049Y-152472D01*
X104141Y-153638D01*
G01X114654Y-167638D02*
X116183Y-168805D01*
X117929Y-169096D01*
X119457Y-168805D01*
X120768Y-167347D01*
X121641Y-165305D01*
Y-151597D01*
G01Y-153930D02*
X120768Y-152763D01*
X119457Y-151888D01*
X117929Y-151597D01*
X116183Y-152180D01*
X115091Y-153346D01*
X114217Y-155388D01*
X113781Y-157430D01*
X113999Y-159180D01*
X114873Y-161222D01*
X116183Y-162680D01*
X117929Y-163263D01*
X119239Y-162971D01*
X120768Y-161805D01*
X121641Y-160639D01*
G01X131936Y-155388D02*
X138923D01*
X138268Y-153346D01*
X137176Y-152180D01*
X135648Y-151597D01*
X134119Y-151888D01*
X132809Y-152763D01*
X131936Y-154805D01*
X131499Y-156555D01*
Y-158305D01*
X131936Y-160055D01*
X133028Y-161805D01*
X134338Y-162971D01*
X135866Y-163263D01*
X137394Y-162680D01*
X138923Y-160930D01*
G01X149654Y-163263D02*
Y-151597D01*
G01Y-153930D02*
X150746Y-152763D01*
X151838Y-151888D01*
X153366Y-151597D01*
X154457Y-151888D01*
X155768Y-152763D01*
G01X183344Y-163263D02*
Y-145763D01*
X188803D01*
X190549Y-146638D01*
X191641Y-147805D01*
X192078Y-150138D01*
X191641Y-152472D01*
X190331Y-153930D01*
X188803Y-154805D01*
X183344D01*
G01X188803D02*
X192078Y-163263D01*
G01X205211Y-151597D02*
Y-163263D01*
G01Y-146930D02*
X204774Y-146638D01*
Y-146055D01*
X205211Y-145763D01*
X205648Y-146055D01*
Y-146638D01*
X205211Y-146930D01*
G01X219436Y-161222D02*
X220528Y-162388D01*
X222056Y-163263D01*
X223366D01*
X224676Y-162680D01*
X225549Y-161805D01*
X225986Y-160639D01*
X225768Y-158888D01*
X224894Y-158013D01*
X220964Y-156263D01*
X220091Y-154221D01*
X220528Y-152763D01*
X221401Y-151888D01*
X222711Y-151597D01*
X224021Y-151888D01*
X225331Y-152763D01*
G01X236936Y-155388D02*
X243923D01*
X243268Y-153346D01*
X242176Y-152180D01*
X240648Y-151597D01*
X239119Y-151888D01*
X237809Y-152763D01*
X236936Y-154805D01*
X236499Y-156555D01*
Y-158305D01*
X236936Y-160055D01*
X238028Y-161805D01*
X239338Y-162971D01*
X240866Y-163263D01*
X242394Y-162680D01*
X243923Y-160930D01*
G01X254654Y-163263D02*
Y-151597D01*
G01Y-153930D02*
X255746Y-152763D01*
X256838Y-151888D01*
X258366Y-151597D01*
X259457Y-151888D01*
X260768Y-152763D01*
G01X297514Y-147222D02*
X296204Y-146346D01*
X294676Y-145763D01*
X292929D01*
X290964Y-146638D01*
X289436Y-148096D01*
X288344Y-149847D01*
X287471Y-152763D01*
X287252Y-155388D01*
X287689Y-158013D01*
X288344Y-159763D01*
X289654Y-161513D01*
X291183Y-162680D01*
X292711Y-163263D01*
X294239D01*
X295768Y-162680D01*
X297078Y-161805D01*
X298170Y-160639D01*
G01X314141Y-163263D02*
Y-151597D01*
G01Y-153638D02*
X313268Y-152472D01*
X311957Y-151888D01*
X310429Y-151597D01*
X308901Y-152180D01*
X307591Y-153346D01*
X306717Y-155096D01*
X306281Y-157430D01*
X306717Y-159763D01*
X307591Y-161513D01*
X308901Y-162680D01*
X310429Y-163263D01*
X311957Y-162971D01*
X313268Y-162097D01*
X314141Y-160930D01*
G01X324654Y-163263D02*
Y-151597D01*
G01Y-153930D02*
X325746Y-152763D01*
X326838Y-151888D01*
X328366Y-151597D01*
X329457Y-151888D01*
X330768Y-152763D01*
G01X349141Y-145763D02*
Y-163263D01*
G01Y-160639D02*
X348268Y-162097D01*
X346957Y-162971D01*
X345429Y-163263D01*
X343683Y-162680D01*
X342373Y-161222D01*
X341499Y-159472D01*
X341281Y-157430D01*
X341499Y-155388D01*
X342373Y-153638D01*
X343683Y-152180D01*
X345429Y-151597D01*
X346957Y-151888D01*
X348049Y-152472D01*
X349141Y-153638D01*
G01X112034Y-118263D02*
Y-100763D01*
X117711Y-115346D01*
X123388Y-100763D01*
Y-118263D01*
G01X135211D02*
X133901Y-117971D01*
X132591Y-116805D01*
X131717Y-114763D01*
X131281Y-112430D01*
X131717Y-110096D01*
X132591Y-108055D01*
X133901Y-106888D01*
X135211Y-106597D01*
X136521Y-106888D01*
X137831Y-108055D01*
X138704Y-110096D01*
X138923Y-112430D01*
X138704Y-114763D01*
X137831Y-116805D01*
X136521Y-117971D01*
X135211Y-118263D01*
G01X156641Y-100763D02*
Y-118263D01*
G01Y-115639D02*
X155768Y-117097D01*
X154457Y-117971D01*
X152929Y-118263D01*
X151183Y-117680D01*
X149873Y-116222D01*
X148999Y-114472D01*
X148781Y-112430D01*
X148999Y-110388D01*
X149873Y-108638D01*
X151183Y-107180D01*
X152929Y-106597D01*
X154457Y-106888D01*
X155549Y-107472D01*
X156641Y-108638D01*
G01X166936Y-110388D02*
X173923D01*
X173268Y-108346D01*
X172176Y-107180D01*
X170648Y-106597D01*
X169119Y-106888D01*
X167809Y-107763D01*
X166936Y-109805D01*
X166499Y-111555D01*
Y-113305D01*
X166936Y-115055D01*
X168028Y-116805D01*
X169338Y-117971D01*
X170866Y-118263D01*
X172394Y-117680D01*
X173923Y-115930D01*
G01X187711Y-118263D02*
Y-100763D01*
G01X402811Y-163263D02*
Y-145763D01*
X400191Y-149263D01*
G01Y-163263D02*
X405431D01*
G01X415508Y-159763D02*
X416817Y-161805D01*
X418564Y-162971D01*
X420529Y-163263D01*
X422276Y-162971D01*
X424023Y-161513D01*
X425114Y-159763D01*
X425333Y-158013D01*
X424896Y-155972D01*
X423368Y-154513D01*
X421839Y-153930D01*
X419874D01*
G01X421839D02*
X423149Y-153055D01*
X424241Y-151597D01*
X424678Y-149847D01*
X424241Y-148096D01*
X423149Y-146638D01*
X421184Y-145763D01*
X419219Y-146055D01*
X417254Y-147222D01*
G01X434099Y-161222D02*
X435628Y-162680D01*
X437374Y-163263D01*
X439121Y-162680D01*
X440649Y-160930D01*
X441741Y-158305D01*
X442178Y-155680D01*
Y-152472D01*
X441741Y-149847D01*
X440649Y-147513D01*
X439339Y-146346D01*
X437811Y-145763D01*
X436064Y-146346D01*
X434754Y-147513D01*
X433881Y-149263D01*
X433444Y-151597D01*
X433881Y-153638D01*
X434973Y-155680D01*
X436283Y-156847D01*
X437811Y-157138D01*
X439557Y-156555D01*
X440868Y-155096D01*
X442178Y-152472D01*
G01X455311Y-163263D02*
Y-145763D01*
X452691Y-149263D01*
G01Y-163263D02*
X457931D01*
G01X469099Y-161222D02*
X470628Y-162680D01*
X472374Y-163263D01*
X474121Y-162680D01*
X475649Y-160930D01*
X476741Y-158305D01*
X477178Y-155680D01*
Y-152472D01*
X476741Y-149847D01*
X475649Y-147513D01*
X474339Y-146346D01*
X472811Y-145763D01*
X471064Y-146346D01*
X469754Y-147513D01*
X468881Y-149263D01*
X468444Y-151597D01*
X468881Y-153638D01*
X469973Y-155680D01*
X471283Y-156847D01*
X472811Y-157138D01*
X474557Y-156555D01*
X475868Y-155096D01*
X477178Y-152472D01*
G01X389694Y-118263D02*
Y-100763D01*
X394934D01*
X396681Y-101638D01*
X397991Y-103680D01*
X398428Y-106013D01*
X397991Y-108346D01*
X396899Y-110096D01*
X394934Y-110972D01*
X389694D01*
G01X416364Y-102222D02*
X415054Y-101346D01*
X413526Y-100763D01*
X411779D01*
X409814Y-101638D01*
X408286Y-103096D01*
X407194Y-104847D01*
X406321Y-107763D01*
X406102Y-110388D01*
X406539Y-113013D01*
X407194Y-114763D01*
X408504Y-116513D01*
X410033Y-117680D01*
X411561Y-118263D01*
X413089D01*
X414618Y-117680D01*
X415928Y-116805D01*
X417020Y-115639D01*
G01X430807Y-108930D02*
X431681Y-108055D01*
X432336Y-106597D01*
X432773Y-104554D01*
X432336Y-102805D01*
X431463Y-101638D01*
X429934Y-100763D01*
X424039D01*
Y-118263D01*
X431244D01*
X432773Y-117097D01*
X433646Y-115346D01*
X434083Y-113305D01*
X433646Y-111263D01*
X432336Y-109513D01*
X430807Y-108930D01*
X424039D01*
G01X440011Y-124096D02*
X453111D01*
G01X459039Y-118263D02*
Y-100763D01*
X469083Y-118263D01*
Y-100763D01*
G01X481561Y-118263D02*
X479814Y-117971D01*
X478286Y-116805D01*
X476976Y-115055D01*
X476102Y-113013D01*
X475666Y-110680D01*
Y-108346D01*
X476102Y-106013D01*
X476976Y-103971D01*
X478286Y-102222D01*
X479814Y-101055D01*
X481561Y-100763D01*
X483307Y-101055D01*
X484836Y-102222D01*
X486146Y-103971D01*
X487020Y-106013D01*
X487456Y-108346D01*
Y-110680D01*
X487020Y-113013D01*
X486146Y-115055D01*
X484836Y-116805D01*
X483307Y-117971D01*
X481561Y-118263D01*
G01X532402Y-100763D02*
X537861Y-118263D01*
X543320Y-100763D01*
G01X559728Y-118263D02*
X550994D01*
Y-100763D01*
X559728D01*
G01X556234Y-109221D02*
X550994D01*
G01X568494Y-118263D02*
Y-100763D01*
X573953D01*
X575699Y-101638D01*
X576791Y-102805D01*
X577228Y-105138D01*
X576791Y-107472D01*
X575481Y-108930D01*
X573953Y-109805D01*
X568494D01*
G01X573953D02*
X577228Y-118263D01*
G01X590361Y-118846D02*
X589924Y-118555D01*
Y-117971D01*
X590361Y-117680D01*
X590798Y-117971D01*
Y-118555D01*
X590361Y-118846D01*
G01X550776Y-160930D02*
X552523Y-162388D01*
X554488Y-163263D01*
X556234D01*
X557981Y-162388D01*
X559291Y-160930D01*
X559946Y-158888D01*
X559509Y-156847D01*
X558418Y-155096D01*
X556453Y-153930D01*
X553833Y-153346D01*
X552304Y-152180D01*
X551649Y-150138D01*
X552086Y-148096D01*
X553178Y-146638D01*
X554706Y-145763D01*
X556234D01*
X557763Y-146346D01*
X559073Y-147805D01*
G01X567402Y-163263D02*
X572861Y-145763D01*
X578320Y-163263D01*
G01X576354Y-157138D02*
X569367D01*
G01X646261Y-145763D02*
X649317Y-163263D01*
X652811Y-145763D01*
X656304Y-163263D01*
X659361Y-145763D01*
G01X665726Y-160930D02*
X667473Y-162388D01*
X669438Y-163263D01*
X671184D01*
X672931Y-162388D01*
X674241Y-160930D01*
X674896Y-158888D01*
X674459Y-156847D01*
X673368Y-155096D01*
X671403Y-153930D01*
X668783Y-153346D01*
X667254Y-152180D01*
X666599Y-150138D01*
X667036Y-148096D01*
X668128Y-146638D01*
X669656Y-145763D01*
X671184D01*
X672713Y-146346D01*
X674023Y-147805D01*
G01X685191Y-145763D02*
X690431D01*
G01X687811D02*
Y-163263D01*
G01X685191D02*
X690431D01*
G01X700944Y-145763D02*
Y-163263D01*
X709678D01*
G01X718008D02*
Y-145763D01*
G01X726304D02*
X718008Y-156555D01*
G01X727614Y-163263D02*
X721719Y-151597D01*
G01X733761Y-169096D02*
X746861D01*
G01X757811Y-145763D02*
Y-163263D01*
G01X752789Y-145763D02*
X762833D01*
G01X665944Y-100763D02*
Y-118263D01*
X674678D01*
G01X691741D02*
Y-106597D01*
G01Y-108638D02*
X690868Y-107472D01*
X689557Y-106888D01*
X688029Y-106597D01*
X686501Y-107180D01*
X685191Y-108346D01*
X684317Y-110096D01*
X683881Y-112430D01*
X684317Y-114763D01*
X685191Y-116513D01*
X686501Y-117680D01*
X688029Y-118263D01*
X689557Y-117971D01*
X690868Y-117097D01*
X691741Y-115930D01*
G01X700726Y-123513D02*
X702036Y-124096D01*
X703783Y-123513D01*
X704874Y-122347D01*
X705748Y-120888D01*
X707057Y-116222D01*
X709896Y-106597D01*
G01X702909D02*
X707057Y-116222D01*
G01X719536Y-110388D02*
X726523D01*
X725868Y-108346D01*
X724776Y-107180D01*
X723248Y-106597D01*
X721719Y-106888D01*
X720409Y-107763D01*
X719536Y-109805D01*
X719099Y-111555D01*
Y-113305D01*
X719536Y-115055D01*
X720628Y-116805D01*
X721938Y-117971D01*
X723466Y-118263D01*
X724994Y-117680D01*
X726523Y-115930D01*
G01X737254Y-118263D02*
Y-106597D01*
G01Y-108930D02*
X738346Y-107763D01*
X739438Y-106888D01*
X740966Y-106597D01*
X742057Y-106888D01*
X743368Y-107763D01*
G01X808058Y-118263D02*
Y-100763D01*
X812424D01*
X814171Y-101638D01*
X815481Y-102805D01*
X816573Y-104554D01*
X817446Y-106597D01*
X817664Y-109513D01*
X817446Y-112430D01*
X816573Y-114472D01*
X815481Y-116222D01*
X814171Y-117388D01*
X812424Y-118263D01*
X808058D01*
G01X827086Y-110388D02*
X834073D01*
X833418Y-108346D01*
X832326Y-107180D01*
X830798Y-106597D01*
X829269Y-106888D01*
X827959Y-107763D01*
X827086Y-109805D01*
X826649Y-111555D01*
Y-113305D01*
X827086Y-115055D01*
X828178Y-116805D01*
X829488Y-117971D01*
X831016Y-118263D01*
X832544Y-117680D01*
X834073Y-115930D01*
G01X844586Y-116222D02*
X845678Y-117388D01*
X847206Y-118263D01*
X848516D01*
X849826Y-117680D01*
X850699Y-116805D01*
X851136Y-115639D01*
X850918Y-113888D01*
X850044Y-113013D01*
X846114Y-111263D01*
X845241Y-109221D01*
X845678Y-107763D01*
X846551Y-106888D01*
X847861Y-106597D01*
X849171Y-106888D01*
X850481Y-107763D01*
G01X865361Y-106597D02*
Y-118263D01*
G01Y-101930D02*
X864924Y-101638D01*
Y-101055D01*
X865361Y-100763D01*
X865798Y-101055D01*
Y-101638D01*
X865361Y-101930D01*
G01X879804Y-122638D02*
X881333Y-123805D01*
X883079Y-124096D01*
X884607Y-123805D01*
X885918Y-122347D01*
X886791Y-120305D01*
Y-106597D01*
G01Y-108930D02*
X885918Y-107763D01*
X884607Y-106888D01*
X883079Y-106597D01*
X881333Y-107180D01*
X880241Y-108346D01*
X879367Y-110388D01*
X878931Y-112430D01*
X879149Y-114180D01*
X880023Y-116222D01*
X881333Y-117680D01*
X883079Y-118263D01*
X884389Y-117971D01*
X885918Y-116805D01*
X886791Y-115639D01*
G01X896649Y-118263D02*
Y-106597D01*
G01Y-109513D02*
X897523Y-108055D01*
X898833Y-106888D01*
X900579Y-106597D01*
X902107Y-106888D01*
X903418Y-108055D01*
X904073Y-110096D01*
Y-118263D01*
G01X914586Y-110388D02*
X921573D01*
X920918Y-108346D01*
X919826Y-107180D01*
X918298Y-106597D01*
X916769Y-106888D01*
X915459Y-107763D01*
X914586Y-109805D01*
X914149Y-111555D01*
Y-113305D01*
X914586Y-115055D01*
X915678Y-116805D01*
X916988Y-117971D01*
X918516Y-118263D01*
X920044Y-117680D01*
X921573Y-115930D01*
G01X932304Y-118263D02*
Y-106597D01*
G01Y-108930D02*
X933396Y-107763D01*
X934488Y-106888D01*
X936016Y-106597D01*
X937107Y-106888D01*
X938418Y-107763D01*
G01X853991Y-145763D02*
X859231D01*
G01X856611D02*
Y-163263D01*
G01X853991D02*
X859231D01*
G01X868652Y-145763D02*
X874111Y-163263D01*
X879570Y-145763D01*
G01X891611Y-163263D02*
Y-155388D01*
X887244Y-145763D01*
G01X895978D02*
X891611Y-155388D01*
G01X979061Y-163263D02*
Y-145763D01*
X976441Y-149263D01*
G01Y-163263D02*
X981681D01*
G01X996561D02*
Y-145763D01*
X993941Y-149263D01*
G01Y-163263D02*
X999181D01*
G01X1010131Y-163846D02*
X1017991Y-145763D01*
G01X1027413Y-148680D02*
X1028723Y-146930D01*
X1030251Y-146055D01*
X1031998Y-145763D01*
X1034181Y-146346D01*
X1035709Y-147805D01*
X1036146Y-149554D01*
X1035928Y-151305D01*
X1035054Y-152763D01*
X1030688Y-155680D01*
X1028723Y-157721D01*
X1027413Y-160639D01*
X1026976Y-163263D01*
X1036146D01*
G01X1044913Y-148680D02*
X1046223Y-146930D01*
X1047751Y-146055D01*
X1049498Y-145763D01*
X1051681Y-146346D01*
X1053209Y-147805D01*
X1053646Y-149554D01*
X1053428Y-151305D01*
X1052554Y-152763D01*
X1048188Y-155680D01*
X1046223Y-157721D01*
X1044913Y-160639D01*
X1044476Y-163263D01*
X1053646D01*
G01X1062631Y-163846D02*
X1070491Y-145763D01*
G01X1079913Y-148680D02*
X1081223Y-146930D01*
X1082751Y-146055D01*
X1084498Y-145763D01*
X1086681Y-146346D01*
X1088209Y-147805D01*
X1088646Y-149554D01*
X1088428Y-151305D01*
X1087554Y-152763D01*
X1083188Y-155680D01*
X1081223Y-157721D01*
X1079913Y-160639D01*
X1079476Y-163263D01*
X1088646D01*
G01X1101561Y-145763D02*
X1099814Y-146346D01*
X1098504Y-147805D01*
X1097631Y-149554D01*
X1096976Y-151888D01*
X1096758Y-154513D01*
X1096976Y-157138D01*
X1097631Y-159472D01*
X1098504Y-161222D01*
X1099814Y-162680D01*
X1101561Y-163263D01*
X1103307Y-162680D01*
X1104618Y-161222D01*
X1105491Y-159472D01*
X1106146Y-157138D01*
X1106364Y-154513D01*
X1106146Y-151888D01*
X1105491Y-149554D01*
X1104618Y-147805D01*
X1103307Y-146346D01*
X1101561Y-145763D01*
G01X1119061Y-163263D02*
Y-145763D01*
X1116441Y-149263D01*
G01Y-163263D02*
X1121681D01*
G01X1131758Y-159763D02*
X1133067Y-161805D01*
X1134814Y-162971D01*
X1136779Y-163263D01*
X1138526Y-162971D01*
X1140273Y-161513D01*
X1141364Y-159763D01*
X1141583Y-158013D01*
X1141146Y-155972D01*
X1139618Y-154513D01*
X1138089Y-153930D01*
X1136124D01*
G01X1138089D02*
X1139399Y-153055D01*
X1140491Y-151597D01*
X1140928Y-149847D01*
X1140491Y-148096D01*
X1139399Y-146638D01*
X1137434Y-145763D01*
X1135469Y-146055D01*
X1133504Y-147222D01*
G01X1026758Y-118263D02*
Y-100763D01*
X1031124D01*
X1032871Y-101638D01*
X1034181Y-102805D01*
X1035273Y-104554D01*
X1036146Y-106597D01*
X1036364Y-109513D01*
X1036146Y-112430D01*
X1035273Y-114472D01*
X1034181Y-116222D01*
X1032871Y-117388D01*
X1031124Y-118263D01*
X1026758D01*
G01X1052991D02*
Y-106597D01*
G01Y-108638D02*
X1052118Y-107472D01*
X1050807Y-106888D01*
X1049279Y-106597D01*
X1047751Y-107180D01*
X1046441Y-108346D01*
X1045567Y-110096D01*
X1045131Y-112430D01*
X1045567Y-114763D01*
X1046441Y-116513D01*
X1047751Y-117680D01*
X1049279Y-118263D01*
X1050807Y-117971D01*
X1052118Y-117097D01*
X1052991Y-115930D01*
G01X1066561Y-100763D02*
Y-118263D01*
G01X1063504Y-106597D02*
X1069618D01*
G01X1080786Y-110388D02*
X1087773D01*
X1087118Y-108346D01*
X1086026Y-107180D01*
X1084498Y-106597D01*
X1082969Y-106888D01*
X1081659Y-107763D01*
X1080786Y-109805D01*
X1080349Y-111555D01*
Y-113305D01*
X1080786Y-115055D01*
X1081878Y-116805D01*
X1083188Y-117971D01*
X1084716Y-118263D01*
X1086244Y-117680D01*
X1087773Y-115930D01*
G01X-20271Y15000D02*
Y676339D01*
G01Y15000D02*
G03X-5271Y0I15000J0D01*
G01Y691339D02*
G03X-20271Y676339I0J-15000D01*
G01X0Y37795D02*
G03X3937Y33858I3937J0D01*
G01X21063Y29921D02*
G03X17126Y33858I-3937J0D01*
G01X3937D02*
X17126D01*
G01X299409Y0D02*
X23031D01*
G01X21063Y1969D02*
X23031Y0D01*
G01X21063Y1969D02*
Y29921D01*
G01X0Y102756D02*
Y37795D01*
G01D02*
G03X-7874I-3937J0D01*
G01X3937Y25984D02*
X13189D01*
G01X-7874Y37795D02*
G03X3937Y25984I11811J0D01*
G01X13189Y0D02*
X-5271D01*
G01X13189Y25984D02*
Y0D01*
G01X3937Y106693D02*
G03X0Y102756I0J-3937D01*
G01X-7874Y68504D02*
G03X0I3937J0D01*
G01X-7874D02*
Y122737D01*
G01X0Y118504D02*
G03X3937Y114567I3937J0D01*
G01Y157382D02*
G03X0Y153445I0J-3937D01*
G01X17126Y157382D02*
G03X21063Y161319I0J3937D01*
G01X0Y118504D02*
Y153445D01*
G01X21063Y219292D02*
Y161319D01*
G01D02*
Y187402D01*
G01X143701Y114567D02*
X3937D01*
G01Y157382D02*
X17126D01*
G01X3937Y106693D02*
X143701D01*
G01X-7874Y153445D02*
Y157382D01*
G01Y153445D02*
G03X0I3937J0D01*
G01Y122737D02*
G03X-7874I-3937J0D01*
G01X-10433Y161070D02*
G03X-7874Y157382I3937J0D01*
G01X-10433Y265210D02*
Y161070D01*
G01X51378Y181496D02*
G03X47441Y177559I0J-3937D01*
G01Y165748D02*
G03X51378Y161811I3937J0D01*
G01X47441Y165748D02*
Y177559D01*
G01X23031Y221260D02*
X21063Y219292D01*
G01X23031Y221260D02*
X63189D01*
G01X0Y272835D02*
G03X3937Y268898I3937J0D01*
G01X21063Y264961D02*
G03X17126Y268898I-3937J0D01*
G01X3937D02*
X17126D01*
G01X299409Y235040D02*
X23031D01*
G01X21063Y237008D02*
X23031Y235040D01*
G01X21063Y237008D02*
Y264961D01*
G01X0Y337796D02*
Y272835D01*
G01D02*
G03X-7874I-3937J0D01*
G01Y268898D02*
G03X-10433Y265210I1378J-3688D01*
G01X-7874Y268898D02*
Y272835D01*
G01X3937Y341733D02*
G03X0Y337796I0J-3937D01*
G01X3937Y341733D02*
X143701D01*
G01X-7874Y303543D02*
Y357781D01*
G01Y303544D02*
G03X0I3937J0D01*
G01X47441Y400788D02*
G03X51378Y396851I3937J0D01*
G01X47441Y400788D02*
Y412599D01*
G01X0Y353544D02*
G03X3937Y349607I3937J0D01*
G01Y392422D02*
G03X0Y388485I0J-3937D01*
G01X17126Y392422D02*
G03X21063Y396359I0J3937D01*
G01X0Y353544D02*
Y388485D01*
G01X21063Y454331D02*
Y396359D01*
G01D02*
Y422441D01*
G01X143701Y349607D02*
X3937D01*
G01Y392422D02*
X17126D01*
G01X-7874Y388480D02*
Y392422D01*
G01Y388485D02*
G03X0I3937J0D01*
G01Y357776D02*
G03X-7874I-3937J0D01*
G01X-10433Y396110D02*
G03X-7874Y392422I3937J0D01*
G01X-10433Y500250D02*
Y396110D01*
G01X51378Y416536D02*
G03X47441Y412599I0J-3937D01*
G01X23031Y456300D02*
X21063Y454331D01*
G01X23031Y456300D02*
X63189D01*
G01X0Y507874D02*
G03X3937Y503937I3937J0D01*
G01X21063Y500000D02*
G03X17126Y503937I-3937J0D01*
G01X3937D02*
X17126D01*
G01X299409Y470079D02*
X23031D01*
G01X21063Y472048D02*
X23031Y470079D01*
G01X21063Y472048D02*
Y500000D01*
G01X0Y572835D02*
Y507874D01*
G01D02*
G03X-7874I-3937J0D01*
G01Y503937D02*
Y507880D01*
G01Y503937D02*
G03X-10433Y500250I1378J-3688D01*
G01X3937Y576772D02*
G03X0Y572835I0J-3937D01*
G01X3937Y576772D02*
X143701D01*
G01X0Y588583D02*
G03X3937Y584646I3937J0D01*
G01X0Y588583D02*
Y623524D01*
G01X143701Y584646D02*
X3937D01*
G01X-7874Y538578D02*
Y592823D01*
G01Y538583D02*
G03X0I3937J0D01*
G01X51378Y651576D02*
G03X47441Y647639I0J-3937D01*
G01Y635828D02*
G03X51378Y631891I3937J0D01*
G01X47441Y635828D02*
Y647639D01*
G01X3937Y627461D02*
G03X0Y623524I0J-3937D01*
G01X17126Y627461D02*
G03X21063Y631398I0J3937D01*
G01Y689371D02*
Y631398D01*
G01D02*
Y657481D01*
G01X3937Y627461D02*
X17126D01*
G01X1830Y651994D02*
G03I-4292J0D01*
G01X-7874Y623517D02*
Y623536D01*
G01X13189Y691339D02*
Y635335D01*
G01X3937D02*
X13189D01*
G01X3937D02*
G03X-7874Y623524I0J-11811D01*
G01D02*
G03X0I3937J0D01*
G01Y592816D02*
G03X-7874I-3937J0D01*
G01X23031Y691339D02*
X21063Y689371D01*
G01X23031Y691339D02*
X63189D01*
G01X13189D02*
X-5271D01*
G01X63189Y161811D02*
G03X67126Y165748I0J3937D01*
G01X73425D02*
G03X77362Y161811I3937J0D01*
G01X89173D02*
G03X93110Y165748I0J3937D01*
G01X99409D02*
G03X103346Y161811I3937J0D01*
G01X63189D02*
X51378D01*
G01X89173D02*
X77362D01*
G01X115157D02*
X103346D01*
G01X89173Y114567D02*
G03Y106693I0J-3937D01*
G01X58465D02*
G03Y114567I0J3937D01*
G01X67126Y177559D02*
G03X63189Y181496I-3937J0D01*
G01X77362D02*
G03X73425Y177559I0J-3937D01*
G01X93110D02*
G03X89173Y181496I-3937J0D01*
G01X103346D02*
G03X99409Y177559I0J-3937D01*
G01X67126D02*
Y165748D01*
G01X73425D02*
Y177559D01*
G01X93110D02*
Y165748D01*
G01X99409D02*
Y177559D01*
G01X103346Y181496D02*
X115157D01*
G01X77362D02*
X89173D01*
G01X51378D02*
X63189D01*
G01X65157Y191930D02*
G03X72638I3740J0D01*
G01X65157Y219292D02*
Y191930D01*
G01X74606Y221260D02*
X72638Y219292D01*
G01D02*
Y191930D01*
G01X65157Y219292D02*
X63189Y221260D01*
G01X74606D02*
X350984D01*
G01X89173Y349607D02*
G03Y341733I0J-3937D01*
G01X58465D02*
G03Y349607I0J3937D01*
G01X63189Y396851D02*
G03X67126Y400788I0J3937D01*
G01X73425D02*
G03X77362Y396851I3937J0D01*
G01X89173D02*
G03X93110Y400788I0J3937D01*
G01X99409D02*
G03X103346Y396851I3937J0D01*
G01X67126Y412599D02*
Y400788D01*
G01X73425D02*
Y412599D01*
G01X93110D02*
Y400788D01*
G01X99409D02*
Y412599D01*
G01X63189Y396851D02*
X51378D01*
G01X89173D02*
X77362D01*
G01X115157D02*
X103346D01*
G01X67126Y412599D02*
G03X63189Y416536I-3937J0D01*
G01X77362D02*
G03X73425Y412599I0J-3937D01*
G01X93110D02*
G03X89173Y416536I-3937J0D01*
G01X103346D02*
G03X99409Y412599I0J-3937D01*
G01X103346Y416536D02*
X115157D01*
G01X77362D02*
X89173D01*
G01X51378D02*
X63189D01*
G01X65157Y426969D02*
G03X72638I3740J0D01*
G01X65157Y454331D02*
Y426969D01*
G01X74606Y456300D02*
X72638Y454331D01*
G01D02*
Y426969D01*
G01X65157Y454331D02*
X63189Y456300D01*
G01X74606D02*
X350984D01*
G01X89173Y584646D02*
G03Y576772I0J-3937D01*
G01X58465D02*
G03Y584646I0J3937D01*
G01X67126Y647639D02*
G03X63189Y651576I-3937J0D01*
G01Y631891D02*
G03X67126Y635828I0J3937D01*
G01X73425D02*
G03X77362Y631891I3937J0D01*
G01Y651576D02*
G03X73425Y647639I0J-3937D01*
G01X93110D02*
G03X89173Y651576I-3937J0D01*
G01Y631891D02*
G03X93110Y635828I0J3937D01*
G01X103346Y651576D02*
G03X99409Y647639I0J-3937D01*
G01Y635828D02*
G03X103346Y631891I3937J0D01*
G01X67126Y647639D02*
Y635828D01*
G01X73425D02*
Y647639D01*
G01X93110D02*
Y635828D01*
G01X99409D02*
Y647639D01*
G01X63189Y631891D02*
X51378D01*
G01X89173D02*
X77362D01*
G01X115157D02*
X103346D01*
G01Y651576D02*
X115157D01*
G01X77362D02*
X89173D01*
G01X51378D02*
X63189D01*
G01X65157Y662009D02*
G03X72638I3740J0D01*
G01X65157Y689371D02*
Y662009D01*
G01X74606Y691339D02*
X72638Y689371D01*
G01D02*
Y662009D01*
G01X65157Y689371D02*
X63189Y691339D01*
G01X74606D02*
X350984D01*
G01X147638Y102756D02*
G03X151575Y98819I3937J0D01*
G01X147638Y102756D02*
G03X143701Y106693I-3937J0D01*
G01X147638Y102756D02*
G03X151575Y98819I3937J0D01*
G01X147638Y102756D02*
G03X143701Y106693I-3937J0D01*
G01X147638Y102756D02*
G03X151575Y98819I3937J0D01*
G01X147638Y102756D02*
G03X143701Y106693I-3937J0D01*
G01X151575Y98819D02*
X222441D01*
G01X115157Y161811D02*
G03X119094Y165748I0J3937D01*
G01X151575Y122441D02*
G03X147638Y118504I0J-3937D01*
G01X143701Y114567D02*
G03X147638Y118504I0J3937D01*
G01X143701Y114567D02*
X112205D01*
G01X143701D02*
G03X147638Y118504I0J3937D01*
G01X151575Y122441D02*
G03X147638Y118504I0J-3937D01*
G01X151575Y122441D02*
G03X147638Y118504I0J-3937D01*
G01X143701Y114567D02*
G03X147638Y118504I0J3937D01*
G01X222441Y122441D02*
X151575D01*
G01X143701Y106693D02*
X112205D01*
G01X119094Y177559D02*
G03X115157Y181496I-3937J0D01*
G01X119094Y177559D02*
Y165748D01*
G01X147638Y337796D02*
G03X151575Y333859I3937J0D01*
G01X147638Y337796D02*
G03X143701Y341733I-3937J0D01*
G01D02*
X112205D01*
G01X147638Y337796D02*
G03X151575Y333859I3937J0D01*
G01X147638Y337796D02*
G03X143701Y341733I-3937J0D01*
G01X147638Y337796D02*
G03X151575Y333859I3937J0D01*
G01X147638Y337796D02*
G03X143701Y341733I-3937J0D01*
G01X151575Y333859D02*
X222441D01*
G01X115157Y396851D02*
G03X119094Y400788I0J3937D01*
G01Y412599D02*
Y400788D01*
G01X151575Y357481D02*
G03X147638Y353544I0J-3937D01*
G01X143701Y349607D02*
G03X147638Y353544I0J3937D01*
G01X143701Y349607D02*
X112205D01*
G01X143701D02*
G03X147638Y353544I0J3937D01*
G01X151575Y357481D02*
G03X147638Y353544I0J-3937D01*
G01X151575Y357481D02*
G03X147638Y353544I0J-3937D01*
G01X143701Y349607D02*
G03X147638Y353544I0J3937D01*
G01X222441Y357481D02*
X151575D01*
G01X119094Y412599D02*
G03X115157Y416536I-3937J0D01*
G01X147638Y572835D02*
G03X151575Y568898I3937J0D01*
G01X147638Y572835D02*
G03X143701Y576772I-3937J0D01*
G01D02*
X112205D01*
G01X147638Y572835D02*
G03X151575Y568898I3937J0D01*
G01X147638Y572835D02*
G03X143701Y576772I-3937J0D01*
G01X147638Y572835D02*
G03X151575Y568898I3937J0D01*
G01X147638Y572835D02*
G03X143701Y576772I-3937J0D01*
G01X151575Y568898D02*
X222441D01*
G01X151575Y592520D02*
G03X147638Y588583I0J-3937D01*
G01X143701Y584646D02*
G03X147638Y588583I0J3937D01*
G01X143701Y584646D02*
X112205D01*
G01X143701D02*
G03X147638Y588583I0J3937D01*
G01X151575Y592520D02*
G03X147638Y588583I0J-3937D01*
G01X151575Y592520D02*
G03X147638Y588583I0J-3937D01*
G01X143701Y584646D02*
G03X147638Y588583I0J3937D01*
G01X119094Y647639D02*
G03X115157Y651576I-3937J0D01*
G01Y631891D02*
G03X119094Y635828I0J3937D01*
G01Y647639D02*
Y635828D01*
G01X222441Y592520D02*
X151575D01*
G01X182603Y26990D02*
Y31990D01*
X184687D01*
X185353Y31740D01*
X185770Y31407D01*
X185937Y30740D01*
X185770Y30073D01*
X185270Y29657D01*
X184687Y29407D01*
X182603D01*
G01X184687D02*
X185937Y26990D01*
G01X189870D02*
X189203Y27073D01*
X188620Y27407D01*
X188120Y27907D01*
X187787Y28490D01*
X187620Y29157D01*
Y29823D01*
X187787Y30490D01*
X188120Y31073D01*
X188620Y31573D01*
X189203Y31907D01*
X189870Y31990D01*
X190537Y31907D01*
X191120Y31573D01*
X191620Y31073D01*
X191953Y30490D01*
X192120Y29823D01*
Y29157D01*
X191953Y28490D01*
X191620Y27907D01*
X191120Y27407D01*
X190537Y27073D01*
X189870Y26990D01*
G01X193720D02*
Y31990D01*
G01X197220D02*
Y26990D01*
G01Y29490D02*
X193720D01*
G01X199320Y27657D02*
X199987Y27240D01*
X200737Y26990D01*
X201403D01*
X202070Y27240D01*
X202570Y27657D01*
X202820Y28240D01*
X202653Y28823D01*
X202237Y29323D01*
X201487Y29657D01*
X200487Y29823D01*
X199903Y30157D01*
X199653Y30740D01*
X199820Y31323D01*
X200237Y31740D01*
X200820Y31990D01*
X201403D01*
X201987Y31823D01*
X202487Y31407D01*
G01X214103Y31573D02*
X213603Y31823D01*
X213020Y31990D01*
X212353D01*
X211603Y31740D01*
X211020Y31323D01*
X210603Y30823D01*
X210270Y29990D01*
X210187Y29240D01*
X210353Y28490D01*
X210603Y27990D01*
X211103Y27490D01*
X211687Y27157D01*
X212270Y26990D01*
X212853D01*
X213437Y27157D01*
X213937Y27407D01*
X214353Y27740D01*
G01X217870Y26990D02*
X217370Y27073D01*
X216870Y27407D01*
X216537Y27990D01*
X216370Y28657D01*
X216537Y29323D01*
X216870Y29907D01*
X217370Y30240D01*
X217870Y30323D01*
X218370Y30240D01*
X218870Y29907D01*
X219203Y29323D01*
X219287Y28657D01*
X219203Y27990D01*
X218870Y27407D01*
X218370Y27073D01*
X217870Y26990D01*
G01X220970D02*
Y30323D01*
G01Y29407D02*
X221220Y29823D01*
X221637Y30157D01*
X222220Y30323D01*
X222803Y30157D01*
X223220Y29823D01*
X223470Y29407D01*
Y26990D01*
G01Y29407D02*
X223720Y29823D01*
X224137Y30157D01*
X224720Y30323D01*
X225303Y30157D01*
X225720Y29823D01*
X225970Y29323D01*
Y26990D01*
G01X227570Y25323D02*
Y30323D01*
G01Y29573D02*
X227987Y29990D01*
X228403Y30240D01*
X229070Y30323D01*
X229653Y30240D01*
X230237Y29823D01*
X230487Y29240D01*
X230570Y28657D01*
X230487Y28073D01*
X230237Y27490D01*
X229737Y27157D01*
X229070Y26990D01*
X228487Y27073D01*
X227903Y27323D01*
X227570Y27657D01*
G01X234670Y26990D02*
Y31990D01*
G01X240270Y30323D02*
Y26990D01*
G01Y31657D02*
X240103Y31740D01*
Y31907D01*
X240270Y31990D01*
X240437Y31907D01*
Y31740D01*
X240270Y31657D01*
G01X247370Y26990D02*
Y30323D01*
G01Y29740D02*
X247037Y30073D01*
X246537Y30240D01*
X245953Y30323D01*
X245370Y30157D01*
X244870Y29823D01*
X244537Y29323D01*
X244370Y28657D01*
X244537Y27990D01*
X244870Y27490D01*
X245370Y27157D01*
X245953Y26990D01*
X246537Y27073D01*
X247037Y27323D01*
X247370Y27657D01*
G01X250053Y26990D02*
Y30323D01*
G01Y29490D02*
X250387Y29907D01*
X250887Y30240D01*
X251553Y30323D01*
X252137Y30240D01*
X252637Y29907D01*
X252887Y29323D01*
Y26990D01*
G01X258403Y29907D02*
X257820Y30240D01*
X257320Y30323D01*
X256653Y30157D01*
X256153Y29823D01*
X255820Y29240D01*
X255737Y28657D01*
X255820Y28073D01*
X256153Y27573D01*
X256653Y27157D01*
X257320Y26990D01*
X257903Y27157D01*
X258403Y27490D01*
G01X261420Y29240D02*
X264087D01*
X263837Y29823D01*
X263420Y30157D01*
X262837Y30323D01*
X262253Y30240D01*
X261753Y29990D01*
X261420Y29407D01*
X261253Y28907D01*
Y28407D01*
X261420Y27907D01*
X261837Y27407D01*
X262337Y27073D01*
X262920Y26990D01*
X263503Y27157D01*
X264087Y27657D01*
G01X209620Y41480D02*
X210787Y36480D01*
X212120Y41480D01*
X213453Y36480D01*
X214620Y41480D01*
G01X217720Y39813D02*
Y36480D01*
G01Y41147D02*
X217553Y41230D01*
Y41397D01*
X217720Y41480D01*
X217887Y41397D01*
Y41230D01*
X217720Y41147D01*
G01X221237Y39813D02*
X222237Y36480D01*
X223320Y39813D01*
X224403Y36480D01*
X225403Y39813D01*
G01X227170Y34980D02*
X227670Y34813D01*
X228337Y34980D01*
X228753Y35313D01*
X229087Y35730D01*
X229587Y37063D01*
X230670Y39813D01*
G01X228003D02*
X229587Y37063D01*
G01X233103Y36480D02*
Y39813D01*
G01Y38980D02*
X233437Y39397D01*
X233937Y39730D01*
X234603Y39813D01*
X235187Y39730D01*
X235687Y39397D01*
X235937Y38813D01*
Y36480D01*
G01X238703D02*
Y39813D01*
G01Y38980D02*
X239037Y39397D01*
X239537Y39730D01*
X240203Y39813D01*
X240787Y39730D01*
X241287Y39397D01*
X241537Y38813D01*
Y36480D01*
G01X222441Y98819D02*
G03X226378Y102756I0J3937D01*
G01X230315Y106693D02*
G03X226378Y102756I0J-3937D01*
G01X230315Y106693D02*
G03X226378Y102756I0J-3937D01*
G01X222441Y98819D02*
G03X226378Y102756I0J3937D01*
G01X222441Y98819D02*
G03X226378Y102756I0J3937D01*
G01X230315Y106693D02*
G03X226378Y102756I0J-3937D01*
G01Y118504D02*
G03X222441Y122441I-3937J0D01*
G01X226378Y118504D02*
G03X230315Y114567I3937J0D01*
G01D02*
X261811D01*
G01X226378Y118504D02*
G03X222441Y122441I-3937J0D01*
G01X226378Y118504D02*
G03X230315Y114567I3937J0D01*
G01X226378Y118504D02*
G03X222441Y122441I-3937J0D01*
G01X226378Y118504D02*
G03X230315Y114567I3937J0D01*
G01X370079D02*
X230315D01*
G01Y106693D02*
X261811D01*
G01X230315D02*
X370079D01*
G01X222441Y333859D02*
G03X226378Y337796I0J3937D01*
G01X230315Y341733D02*
G03X226378Y337796I0J-3937D01*
G01X230315Y341733D02*
X261811D01*
G01X230315D02*
G03X226378Y337796I0J-3937D01*
G01X222441Y333859D02*
G03X226378Y337796I0J3937D01*
G01X222441Y333859D02*
G03X226378Y337796I0J3937D01*
G01X230315Y341733D02*
G03X226378Y337796I0J-3937D01*
G01X230315Y341733D02*
X370079D01*
G01X226378Y353544D02*
G03X222441Y357481I-3937J0D01*
G01X226378Y353544D02*
G03X230315Y349607I3937J0D01*
G01D02*
X261811D01*
G01X226378Y353544D02*
G03X222441Y357481I-3937J0D01*
G01X226378Y353544D02*
G03X230315Y349607I3937J0D01*
G01X226378Y353544D02*
G03X222441Y357481I-3937J0D01*
G01X226378Y353544D02*
G03X230315Y349607I3937J0D01*
G01X370079D02*
X230315D01*
G01X222441Y568898D02*
G03X226378Y572835I0J3937D01*
G01X230315Y576772D02*
G03X226378Y572835I0J-3937D01*
G01X230315Y576772D02*
X261811D01*
G01X230315D02*
G03X226378Y572835I0J-3937D01*
G01X222441Y568898D02*
G03X226378Y572835I0J3937D01*
G01X222441Y568898D02*
G03X226378Y572835I0J3937D01*
G01X230315Y576772D02*
G03X226378Y572835I0J-3937D01*
G01X230315Y576772D02*
X370079D01*
G01X226378Y588583D02*
G03X222441Y592520I-3937J0D01*
G01X226378Y588583D02*
G03X230315Y584646I3937J0D01*
G01D02*
X261811D01*
G01X226378Y588583D02*
G03X222441Y592520I-3937J0D01*
G01X226378Y588583D02*
G03X230315Y584646I3937J0D01*
G01X226378Y588583D02*
G03X222441Y592520I-3937J0D01*
G01X226378Y588583D02*
G03X230315Y584646I3937J0D01*
G01X370079D02*
X230315D01*
G01X280906Y43701D02*
G03X284843Y39764I3937J0D01*
G01X270669D02*
G03X274606Y43701I0J3937D01*
G01X254921D02*
G03X258858Y39764I3937J0D01*
G01X270669D02*
X258858D01*
G01X296654D02*
X284843D01*
G01Y59449D02*
G03X280906Y55512I0J-3937D01*
G01X258858Y59449D02*
G03X254921Y55512I0J-3937D01*
G01X274606D02*
G03X270669Y59449I-3937J0D01*
G01X280906Y43701D02*
Y55512D01*
G01X274606D02*
Y43701D01*
G01X254921D02*
Y55512D01*
G01X284843Y59449D02*
X296654D01*
G01X258858D02*
X270669D01*
G01X284843Y106693D02*
G03Y114567I0J3937D01*
G01X280906Y278741D02*
G03X284843Y274804I3937J0D01*
G01X270669D02*
G03X274606Y278741I0J3937D01*
G01X254921D02*
G03X258858Y274804I3937J0D01*
G01X280906Y278741D02*
Y290552D01*
G01X274606D02*
Y278741D01*
G01X254921D02*
Y290552D01*
G01X270669Y274804D02*
X258858D01*
G01X296654D02*
X284843D01*
G01Y294489D02*
G03X280906Y290552I0J-3937D01*
G01X258858Y294489D02*
G03X254921Y290552I0J-3937D01*
G01X274606D02*
G03X270669Y294489I-3937J0D01*
G01X284843D02*
X296654D01*
G01X258858D02*
X270669D01*
G01X284843Y341733D02*
G03Y349607I0J3937D01*
G01X280906Y513780D02*
G03X284843Y509843I3937J0D01*
G01Y529528D02*
G03X280906Y525591I0J-3937D01*
G01X270669Y509843D02*
G03X274606Y513780I0J3937D01*
G01X254921D02*
G03X258858Y509843I3937J0D01*
G01Y529528D02*
G03X254921Y525591I0J-3937D01*
G01X274606D02*
G03X270669Y529528I-3937J0D01*
G01X280906Y513780D02*
Y525591D01*
G01X274606D02*
Y513780D01*
G01X254921D02*
Y525591D01*
G01X284843Y529528D02*
X296654D01*
G01X258858D02*
X270669D01*
G01Y509843D02*
X258858D01*
G01X296654D02*
X284843D01*
G01Y576772D02*
G03Y584646I0J3937D01*
G01X322638Y39764D02*
G03X326575Y43701I0J3937D01*
G01X306890D02*
G03X310827Y39764I3937J0D01*
G01X296654D02*
G03X300591Y43701I0J3937D01*
G01X322638Y39764D02*
X310827D01*
G01X308858Y29331D02*
G03X301378I-3740J0D01*
G01X350984Y0D02*
X352953Y1969D01*
G01X308858D02*
Y29331D01*
G01X299409Y0D02*
X301378Y1969D01*
G01D02*
Y29331D01*
G01X308858Y1969D02*
X310827Y0D01*
G01X350984D02*
X310827D01*
G01Y59449D02*
G03X306890Y55512I0J-3937D01*
G01X326575D02*
G03X322638Y59449I-3937J0D01*
G01X300591Y55512D02*
G03X296654Y59449I-3937J0D01*
G01X326575Y55512D02*
Y43701D01*
G01X306890D02*
Y55512D01*
G01X300591D02*
Y43701D01*
G01X310827Y59449D02*
X322638D01*
G01X315551Y114567D02*
G03Y106693I0J-3937D01*
G01X352953Y219292D02*
X350984Y221260D01*
G01X322638Y274804D02*
G03X326575Y278741I0J3937D01*
G01X306890D02*
G03X310827Y274804I3937J0D01*
G01X296654D02*
G03X300591Y278741I0J3937D01*
G01X326575Y290552D02*
Y278741D01*
G01X306890D02*
Y290552D01*
G01X300591D02*
Y278741D01*
G01X322638Y274804D02*
X310827D01*
G01X308858Y264370D02*
G03X301378I-3740J0D01*
G01X350984Y235040D02*
X352953Y237008D01*
G01X308858D02*
Y264370D01*
G01X299409Y235040D02*
X301378Y237008D01*
G01D02*
Y264370D01*
G01X308858Y237008D02*
X310827Y235040D01*
G01X350984D02*
X310827D01*
G01Y294489D02*
G03X306890Y290552I0J-3937D01*
G01X326575D02*
G03X322638Y294489I-3937J0D01*
G01X300591Y290552D02*
G03X296654Y294489I-3937J0D01*
G01X310827D02*
X322638D01*
G01X315551Y349607D02*
G03Y341733I0J-3937D01*
G01X352953Y454331D02*
X350984Y456300D01*
G01X322638Y509843D02*
G03X326575Y513780I0J3937D01*
G01X306890D02*
G03X310827Y509843I3937J0D01*
G01Y529528D02*
G03X306890Y525591I0J-3937D01*
G01X326575D02*
G03X322638Y529528I-3937J0D01*
G01X300591Y525591D02*
G03X296654Y529528I-3937J0D01*
G01Y509843D02*
G03X300591Y513780I0J3937D01*
G01X326575Y525591D02*
Y513780D01*
G01X306890D02*
Y525591D01*
G01X300591D02*
Y513780D01*
G01X310827Y529528D02*
X322638D01*
G01Y509843D02*
X310827D01*
G01X308858Y499410D02*
G03X301378I-3740J0D01*
G01X350984Y470079D02*
X352953Y472048D01*
G01X308858D02*
Y499410D01*
G01X299409Y470079D02*
X301378Y472048D01*
G01D02*
Y499410D01*
G01X308858Y472048D02*
X310827Y470079D01*
G01X350984D02*
X310827D01*
G01X315551Y584646D02*
G03Y576772I0J-3937D01*
G01X352953Y689371D02*
X350984Y691339D01*
G01X381890Y37795D02*
G03X385827Y33858I3937J0D01*
G01X402953Y29921D02*
G03X399016Y33858I-3937J0D01*
G01X385827D02*
X399016D01*
G01X681299Y0D02*
X404921D01*
G01X402953Y1969D02*
X404921Y0D01*
G01X402953Y1969D02*
Y29921D01*
G01X381890Y102756D02*
Y37795D01*
G01X352953Y1969D02*
Y59941D01*
G01D02*
Y33858D01*
G01X385827Y106693D02*
G03X381890Y102756I0J-3937D01*
G01X374016D02*
G03X370079Y106693I-3937J0D01*
G01Y63878D02*
G03X374016Y67815I0J3937D01*
G01X356890Y63878D02*
G03X352953Y59941I0J-3937D01*
G01X374016Y102756D02*
Y67815D01*
G01X370079Y63878D02*
X356890D01*
G01X374016Y98524D02*
G03X381890I3937J0D01*
G01Y67815D02*
G03X374016I-3937J0D01*
G01X385827Y106693D02*
X525591D01*
G01X370079Y114567D02*
G03X374016Y118504I0J3937D01*
G01D02*
Y183465D01*
G01X381890Y118504D02*
G03X385827Y114567I3937J0D01*
G01Y157382D02*
G03X381890Y153445I0J-3937D01*
G01X399016Y157382D02*
G03X402953Y161319I0J3937D01*
G01X381890Y118504D02*
Y153445D01*
G01X402953Y219292D02*
Y161319D01*
G01D02*
Y187402D01*
G01X525591Y114567D02*
X385827D01*
G01Y157382D02*
X399016D01*
G01X374016Y153445D02*
G03X381890I3937J0D01*
G01Y122737D02*
G03X374016I-3937J0D01*
G01Y183465D02*
G03X370079Y187402I-3937J0D01*
G01X352953Y191339D02*
G03X356890Y187402I3937J0D01*
G01X370079D02*
X356890D01*
G01X352953Y219292D02*
Y191339D01*
G01X404921Y221260D02*
X402953Y219292D01*
G01X404921Y221260D02*
X445079D01*
G01X352953Y237008D02*
Y294981D01*
G01D02*
Y268898D01*
G01X381890Y272835D02*
G03X385827Y268898I3937J0D01*
G01X402953Y264961D02*
G03X399016Y268898I-3937J0D01*
G01X385827D02*
X399016D01*
G01X681299Y235040D02*
X404921D01*
G01X402953Y237008D02*
X404921Y235040D01*
G01X402953Y237008D02*
Y264961D01*
G01X381890Y337796D02*
Y272835D01*
G01X374016Y337796D02*
G03X370079Y341733I-3937J0D01*
G01Y298918D02*
G03X374016Y302855I0J3937D01*
G01X356890Y298918D02*
G03X352953Y294981I0J-3937D01*
G01X374016Y337796D02*
Y302855D01*
G01X370079Y298918D02*
X356890D01*
G01X385827Y341733D02*
G03X381890Y337796I0J-3937D01*
G01X385827Y341733D02*
X525591D01*
G01X374016Y333563D02*
G03X381890I3937J0D01*
G01Y302855D02*
G03X374016I-3937J0D01*
G01X381890Y353544D02*
G03X385827Y349607I3937J0D01*
G01Y392422D02*
G03X381890Y388485I0J-3937D01*
G01X399016Y392422D02*
G03X402953Y396359I0J3937D01*
G01X381890Y353544D02*
Y388485D01*
G01X402953Y454331D02*
Y396359D01*
G01D02*
Y422441D01*
G01X525591Y349607D02*
X385827D01*
G01Y392422D02*
X399016D01*
G01X370079Y349607D02*
G03X374016Y353544I0J3937D01*
G01D02*
Y418504D01*
G01Y388485D02*
G03X381890I3937J0D01*
G01Y357776D02*
G03X374016I-3937J0D01*
G01X404921Y456300D02*
X402953Y454331D01*
G01X404921Y456300D02*
X445079D01*
G01X374016Y418504D02*
G03X370079Y422441I-3937J0D01*
G01X352953Y426378D02*
G03X356890Y422441I3937J0D01*
G01X370079D02*
X356890D01*
G01X352953Y454331D02*
Y426378D01*
G01Y472048D02*
Y530020D01*
G01D02*
Y503937D01*
G01X381890Y507874D02*
G03X385827Y503937I3937J0D01*
G01X402953Y500000D02*
G03X399016Y503937I-3937J0D01*
G01X385827D02*
X399016D01*
G01X681299Y470079D02*
X404921D01*
G01X402953Y472048D02*
X404921Y470079D01*
G01X402953Y472048D02*
Y500000D01*
G01X381890Y572835D02*
Y507874D01*
G01X374016Y572835D02*
G03X370079Y576772I-3937J0D01*
G01Y533957D02*
G03X374016Y537894I0J3937D01*
G01X356890Y533957D02*
G03X352953Y530020I0J-3937D01*
G01X374016Y572835D02*
Y537894D01*
G01X370079Y533957D02*
X356890D01*
G01X385827Y576772D02*
G03X381890Y572835I0J-3937D01*
G01X385827Y576772D02*
X525591D01*
G01X381890Y588583D02*
G03X385827Y584646I3937J0D01*
G01X381890Y588583D02*
Y623524D01*
G01X525591Y584646D02*
X385827D01*
G01X370079D02*
G03X374016Y588583I0J3937D01*
G01D02*
Y653544D01*
G01Y568603D02*
G03X381890I3937J0D01*
G01Y537894D02*
G03X374016I-3937J0D01*
G01X385827Y627461D02*
G03X381890Y623524I0J-3937D01*
G01X399016Y627461D02*
G03X402953Y631398I0J3937D01*
G01Y689371D02*
Y631398D01*
G01D02*
Y657481D01*
G01X385827Y627461D02*
X399016D01*
G01X374016Y623524D02*
G03X381890I3937J0D01*
G01Y592816D02*
G03X374016I-3937J0D01*
G01X404921Y691339D02*
X402953Y689371D01*
G01X404921Y691339D02*
X445079D01*
G01X374016Y653544D02*
G03X370079Y657481I-3937J0D01*
G01X352953Y661418D02*
G03X356890Y657481I3937J0D01*
G01X370079D02*
X356890D01*
G01X352953Y689371D02*
Y661418D01*
G01X445079Y161811D02*
G03X449016Y165748I0J3937D01*
G01X429331D02*
G03X433268Y161811I3937J0D01*
G01X455315Y165748D02*
G03X459252Y161811I3937J0D01*
G01X471063D02*
G03X475000Y165748I0J3937D01*
G01X445079Y161811D02*
X433268D01*
G01X471063D02*
X459252D01*
G01X471063Y114567D02*
G03Y106693I0J-3937D01*
G01X440354D02*
G03Y114567I0J3937D01*
G01X433268Y181496D02*
G03X429331Y177559I0J-3937D01*
G01X449016D02*
G03X445079Y181496I-3937J0D01*
G01X459252D02*
G03X455315Y177559I0J-3937D01*
G01X475000D02*
G03X471063Y181496I-3937J0D01*
G01X429331Y165748D02*
Y177559D01*
G01X449016D02*
Y165748D01*
G01X455315D02*
Y177559D01*
G01X459252Y181496D02*
X471063D01*
G01X433268D02*
X445079D01*
G01X447047Y191930D02*
G03X454528I3740J0D01*
G01X447047Y219292D02*
Y191930D01*
G01X456496Y221260D02*
X454528Y219292D01*
G01D02*
Y191930D01*
G01X447047Y219292D02*
X445079Y221260D01*
G01X456496D02*
X732874D01*
G01X471063Y349607D02*
G03Y341733I0J-3937D01*
G01X440354D02*
G03Y349607I0J3937D01*
G01X445079Y396851D02*
G03X449016Y400788I0J3937D01*
G01X429331D02*
G03X433268Y396851I3937J0D01*
G01X455315Y400788D02*
G03X459252Y396851I3937J0D01*
G01X471063D02*
G03X475000Y400788I0J3937D01*
G01X429331D02*
Y412599D01*
G01X449016D02*
Y400788D01*
G01X455315D02*
Y412599D01*
G01X445079Y396851D02*
X433268D01*
G01X471063D02*
X459252D01*
G01X433268Y416536D02*
G03X429331Y412599I0J-3937D01*
G01X449016D02*
G03X445079Y416536I-3937J0D01*
G01X459252D02*
G03X455315Y412599I0J-3937D01*
G01X475000D02*
G03X471063Y416536I-3937J0D01*
G01X459252D02*
X471063D01*
G01X433268D02*
X445079D01*
G01X447047Y426969D02*
G03X454528I3740J0D01*
G01X447047Y454331D02*
Y426969D01*
G01X456496Y456300D02*
X454528Y454331D01*
G01D02*
Y426969D01*
G01X447047Y454331D02*
X445079Y456300D01*
G01X456496D02*
X732874D01*
G01X471063Y584646D02*
G03Y576772I0J-3937D01*
G01X440354D02*
G03Y584646I0J3937D01*
G01X433268Y651576D02*
G03X429331Y647639I0J-3937D01*
G01X449016D02*
G03X445079Y651576I-3937J0D01*
G01Y631891D02*
G03X449016Y635828I0J3937D01*
G01X429331D02*
G03X433268Y631891I3937J0D01*
G01X455315Y635828D02*
G03X459252Y631891I3937J0D01*
G01Y651576D02*
G03X455315Y647639I0J-3937D01*
G01X475000D02*
G03X471063Y651576I-3937J0D01*
G01Y631891D02*
G03X475000Y635828I0J3937D01*
G01X429331D02*
Y647639D01*
G01X449016D02*
Y635828D01*
G01X455315D02*
Y647639D01*
G01X445079Y631891D02*
X433268D01*
G01X471063D02*
X459252D01*
G01Y651576D02*
X471063D01*
G01X433268D02*
X445079D01*
G01X447047Y662009D02*
G03X454528I3740J0D01*
G01X447047Y689371D02*
Y662009D01*
G01X456496Y691339D02*
X454528Y689371D01*
G01D02*
Y662009D01*
G01X447047Y689371D02*
X445079Y691339D01*
G01X456496D02*
X732874D01*
G01X529528Y102756D02*
G03X533465Y98819I3937J0D01*
G01X529528Y102756D02*
G03X525591Y106693I-3937J0D01*
G01X529528Y102756D02*
G03X533465Y98819I3937J0D01*
G01X529528Y102756D02*
G03X525591Y106693I-3937J0D01*
G01X529528Y102756D02*
G03X533465Y98819I3937J0D01*
G01X529528Y102756D02*
G03X525591Y106693I-3937J0D01*
G01X533465Y98819D02*
X604331D01*
G01X525591Y106693D02*
X494094D01*
G01X497047Y161811D02*
G03X500984Y165748I0J3937D01*
G01X481299D02*
G03X485236Y161811I3937J0D01*
G01X497047D02*
X485236D01*
G01X533465Y122441D02*
G03X529528Y118504I0J-3937D01*
G01X525591Y114567D02*
G03X529528Y118504I0J3937D01*
G01X525591Y114567D02*
X494094D01*
G01X525591D02*
G03X529528Y118504I0J3937D01*
G01X533465Y122441D02*
G03X529528Y118504I0J-3937D01*
G01X533465Y122441D02*
G03X529528Y118504I0J-3937D01*
G01X525591Y114567D02*
G03X529528Y118504I0J3937D01*
G01X604331Y122441D02*
X533465D01*
G01X485236Y181496D02*
G03X481299Y177559I0J-3937D01*
G01X500984D02*
G03X497047Y181496I-3937J0D01*
G01X475000Y177559D02*
Y165748D01*
G01X481299D02*
Y177559D01*
G01X500984D02*
Y165748D01*
G01X485236Y181496D02*
X497047D01*
G01X529528Y337796D02*
G03X533465Y333859I3937J0D01*
G01X529528Y337796D02*
G03X525591Y341733I-3937J0D01*
G01D02*
X494094D01*
G01X529528Y337796D02*
G03X533465Y333859I3937J0D01*
G01X529528Y337796D02*
G03X525591Y341733I-3937J0D01*
G01X529528Y337796D02*
G03X533465Y333859I3937J0D01*
G01X529528Y337796D02*
G03X525591Y341733I-3937J0D01*
G01X533465Y333859D02*
X604331D01*
G01X497047Y396851D02*
G03X500984Y400788I0J3937D01*
G01X481299D02*
G03X485236Y396851I3937J0D01*
G01X475000Y412599D02*
Y400788D01*
G01X481299D02*
Y412599D01*
G01X500984D02*
Y400788D01*
G01X497047Y396851D02*
X485236D01*
G01X533465Y357481D02*
G03X529528Y353544I0J-3937D01*
G01X525591Y349607D02*
G03X529528Y353544I0J3937D01*
G01X525591Y349607D02*
X494094D01*
G01X525591D02*
G03X529528Y353544I0J3937D01*
G01X533465Y357481D02*
G03X529528Y353544I0J-3937D01*
G01X533465Y357481D02*
G03X529528Y353544I0J-3937D01*
G01X525591Y349607D02*
G03X529528Y353544I0J3937D01*
G01X604331Y357481D02*
X533465D01*
G01X485236Y416536D02*
G03X481299Y412599I0J-3937D01*
G01X500984D02*
G03X497047Y416536I-3937J0D01*
G01X485236D02*
X497047D01*
G01X529528Y572835D02*
G03X533465Y568898I3937J0D01*
G01X529528Y572835D02*
G03X525591Y576772I-3937J0D01*
G01D02*
X494094D01*
G01X529528Y572835D02*
G03X533465Y568898I3937J0D01*
G01X529528Y572835D02*
G03X525591Y576772I-3937J0D01*
G01X529528Y572835D02*
G03X533465Y568898I3937J0D01*
G01X529528Y572835D02*
G03X525591Y576772I-3937J0D01*
G01X533465Y568898D02*
X604331D01*
G01X533465Y592520D02*
G03X529528Y588583I0J-3937D01*
G01X525591Y584646D02*
G03X529528Y588583I0J3937D01*
G01X525591Y584646D02*
X494094D01*
G01X525591D02*
G03X529528Y588583I0J3937D01*
G01X533465Y592520D02*
G03X529528Y588583I0J-3937D01*
G01X533465Y592520D02*
G03X529528Y588583I0J-3937D01*
G01X525591Y584646D02*
G03X529528Y588583I0J3937D01*
G01X485236Y651576D02*
G03X481299Y647639I0J-3937D01*
G01X500984D02*
G03X497047Y651576I-3937J0D01*
G01Y631891D02*
G03X500984Y635828I0J3937D01*
G01X481299D02*
G03X485236Y631891I3937J0D01*
G01X475000Y647639D02*
Y635828D01*
G01X481299D02*
Y647639D01*
G01X500984D02*
Y635828D01*
G01X497047Y631891D02*
X485236D01*
G01Y651576D02*
X497047D01*
G01X604331Y592520D02*
X533465D01*
G01X652559Y39764D02*
G03X656496Y43701I0J3937D01*
G01X636811D02*
G03X640748Y39764I3937J0D01*
G01X652559D02*
X640748D01*
G01Y59449D02*
G03X636811Y55512I0J-3937D01*
G01X656496D02*
G03X652559Y59449I-3937J0D01*
G01X656496Y55512D02*
Y43701D01*
G01X636811D02*
Y55512D01*
G01X640748Y59449D02*
X652559D01*
G01X604331Y98819D02*
G03X608268Y102756I0J3937D01*
G01X612205Y106693D02*
G03X608268Y102756I0J-3937D01*
G01X612205Y106693D02*
G03X608268Y102756I0J-3937D01*
G01X604331Y98819D02*
G03X608268Y102756I0J3937D01*
G01X604331Y98819D02*
G03X608268Y102756I0J3937D01*
G01X612205Y106693D02*
G03X608268Y102756I0J-3937D01*
G01X612205Y106693D02*
X643701D01*
G01X612205D02*
X751969D01*
G01X608268Y118504D02*
G03X604331Y122441I-3937J0D01*
G01X608268Y118504D02*
G03X612205Y114567I3937J0D01*
G01D02*
X643701D01*
G01X608268Y118504D02*
G03X604331Y122441I-3937J0D01*
G01X608268Y118504D02*
G03X612205Y114567I3937J0D01*
G01X608268Y118504D02*
G03X604331Y122441I-3937J0D01*
G01X608268Y118504D02*
G03X612205Y114567I3937J0D01*
G01X751969D02*
X612205D01*
G01X652559Y274804D02*
G03X656496Y278741I0J3937D01*
G01X636811D02*
G03X640748Y274804I3937J0D01*
G01X656496Y290552D02*
Y278741D01*
G01X636811D02*
Y290552D01*
G01X652559Y274804D02*
X640748D01*
G01Y294489D02*
G03X636811Y290552I0J-3937D01*
G01X656496D02*
G03X652559Y294489I-3937J0D01*
G01X640748D02*
X652559D01*
G01X604331Y333859D02*
G03X608268Y337796I0J3937D01*
G01X612205Y341733D02*
G03X608268Y337796I0J-3937D01*
G01X612205Y341733D02*
X643701D01*
G01X612205D02*
G03X608268Y337796I0J-3937D01*
G01X604331Y333859D02*
G03X608268Y337796I0J3937D01*
G01X604331Y333859D02*
G03X608268Y337796I0J3937D01*
G01X612205Y341733D02*
G03X608268Y337796I0J-3937D01*
G01X612205Y341733D02*
X751969D01*
G01X608268Y353544D02*
G03X604331Y357481I-3937J0D01*
G01X608268Y353544D02*
G03X612205Y349607I3937J0D01*
G01D02*
X643701D01*
G01X608268Y353544D02*
G03X604331Y357481I-3937J0D01*
G01X608268Y353544D02*
G03X612205Y349607I3937J0D01*
G01X608268Y353544D02*
G03X604331Y357481I-3937J0D01*
G01X608268Y353544D02*
G03X612205Y349607I3937J0D01*
G01X751969D02*
X612205D01*
G01X652559Y509843D02*
G03X656496Y513780I0J3937D01*
G01X636811D02*
G03X640748Y509843I3937J0D01*
G01Y529528D02*
G03X636811Y525591I0J-3937D01*
G01X656496D02*
G03X652559Y529528I-3937J0D01*
G01X656496Y525591D02*
Y513780D01*
G01X636811D02*
Y525591D01*
G01X640748Y529528D02*
X652559D01*
G01Y509843D02*
X640748D01*
G01X604331Y568898D02*
G03X608268Y572835I0J3937D01*
G01X612205Y576772D02*
G03X608268Y572835I0J-3937D01*
G01X612205Y576772D02*
X643701D01*
G01X612205D02*
G03X608268Y572835I0J-3937D01*
G01X604331Y568898D02*
G03X608268Y572835I0J3937D01*
G01X604331Y568898D02*
G03X608268Y572835I0J3937D01*
G01X612205Y576772D02*
G03X608268Y572835I0J-3937D01*
G01X612205Y576772D02*
X751969D01*
G01X608268Y588583D02*
G03X604331Y592520I-3937J0D01*
G01X608268Y588583D02*
G03X612205Y584646I3937J0D01*
G01D02*
X643701D01*
G01X608268Y588583D02*
G03X604331Y592520I-3937J0D01*
G01X608268Y588583D02*
G03X612205Y584646I3937J0D01*
G01X608268Y588583D02*
G03X604331Y592520I-3937J0D01*
G01X608268Y588583D02*
G03X612205Y584646I3937J0D01*
G01X751969D02*
X612205D01*
G01X704528Y39764D02*
G03X708465Y43701I0J3937D01*
G01X688780D02*
G03X692717Y39764I3937J0D01*
G01X678543D02*
G03X682480Y43701I0J3937D01*
G01X662795D02*
G03X666732Y39764I3937J0D01*
G01X678543D02*
X666732D01*
G01X704528D02*
X692717D01*
G01X690748Y29331D02*
G03X683268I-3740J0D01*
G01X690748Y1969D02*
Y29331D01*
G01X681299Y0D02*
X683268Y1969D01*
G01D02*
Y29331D01*
G01X690748Y1969D02*
X692717Y0D01*
G01X732874D02*
X692717D01*
G01Y59449D02*
G03X688780Y55512I0J-3937D01*
G01X708465D02*
G03X704528Y59449I-3937J0D01*
G01X682480Y55512D02*
G03X678543Y59449I-3937J0D01*
G01X666732D02*
G03X662795Y55512I0J-3937D01*
G01X708465D02*
Y43701D01*
G01X688780D02*
Y55512D01*
G01X682480D02*
Y43701D01*
G01X662795D02*
Y55512D01*
G01X692717Y59449D02*
X704528D01*
G01X666732D02*
X678543D01*
G01X697441Y114567D02*
G03Y106693I0J-3937D01*
G01X666732D02*
G03Y114567I0J3937D01*
G01X704528Y274804D02*
G03X708465Y278741I0J3937D01*
G01X688780D02*
G03X692717Y274804I3937J0D01*
G01X678543D02*
G03X682480Y278741I0J3937D01*
G01X662795D02*
G03X666732Y274804I3937J0D01*
G01X708465Y290552D02*
Y278741D01*
G01X688780D02*
Y290552D01*
G01X682480D02*
Y278741D01*
G01X662795D02*
Y290552D01*
G01X678543Y274804D02*
X666732D01*
G01X704528D02*
X692717D01*
G01X690748Y264370D02*
G03X683268I-3740J0D01*
G01X690748Y237008D02*
Y264370D01*
G01X681299Y235040D02*
X683268Y237008D01*
G01D02*
Y264370D01*
G01X690748Y237008D02*
X692717Y235040D01*
G01X732874D02*
X692717D01*
G01Y294489D02*
G03X688780Y290552I0J-3937D01*
G01X708465D02*
G03X704528Y294489I-3937J0D01*
G01X682480Y290552D02*
G03X678543Y294489I-3937J0D01*
G01X666732D02*
G03X662795Y290552I0J-3937D01*
G01X692717Y294489D02*
X704528D01*
G01X666732D02*
X678543D01*
G01X697441Y349607D02*
G03Y341733I0J-3937D01*
G01X666732D02*
G03Y349607I0J3937D01*
G01X704528Y509843D02*
G03X708465Y513780I0J3937D01*
G01X688780D02*
G03X692717Y509843I3937J0D01*
G01Y529528D02*
G03X688780Y525591I0J-3937D01*
G01X708465D02*
G03X704528Y529528I-3937J0D01*
G01X682480Y525591D02*
G03X678543Y529528I-3937J0D01*
G01Y509843D02*
G03X682480Y513780I0J3937D01*
G01X662795D02*
G03X666732Y509843I3937J0D01*
G01Y529528D02*
G03X662795Y525591I0J-3937D01*
G01X708465D02*
Y513780D01*
G01X688780D02*
Y525591D01*
G01X682480D02*
Y513780D01*
G01X662795D02*
Y525591D01*
G01X692717Y529528D02*
X704528D01*
G01X666732D02*
X678543D01*
G01Y509843D02*
X666732D01*
G01X704528D02*
X692717D01*
G01X690748Y499410D02*
G03X683268I-3740J0D01*
G01X690748Y472048D02*
Y499410D01*
G01X681299Y470079D02*
X683268Y472048D01*
G01D02*
Y499410D01*
G01X690748Y472048D02*
X692717Y470079D01*
G01X732874D02*
X692717D01*
G01X697441Y584646D02*
G03Y576772I0J-3937D01*
G01X666732D02*
G03Y584646I0J3937D01*
G01X734843Y1969D02*
Y59941D01*
G01D02*
Y33858D01*
G01X732874Y0D02*
X734843Y1969D01*
G01X762744Y17317D02*
G03I-4292J0D01*
G01X775591Y553149D02*
Y15000D01*
G01X760591Y0D02*
G03X775591Y15000I0J15000D01*
G01X742717Y0D02*
Y56004D01*
G01Y0D02*
X760591D01*
G01X755906Y102756D02*
G03X751969Y106693I-3937J0D01*
G01Y63878D02*
G03X755906Y67815I0J3937D01*
G01X738780Y63878D02*
G03X734843Y59941I0J-3937D01*
G01X755906Y102756D02*
Y67815D01*
G01X751969Y63878D02*
X738780D01*
G01X763780Y152761D02*
Y98517D01*
G01Y67822D02*
Y67803D01*
G01X751969Y56004D02*
X742717D01*
G01X751969D02*
G03X763780Y67815I0J11811D01*
G01D02*
G03X755906I-3937J0D01*
G01Y98524D02*
G03X763780I3937J0D01*
G01X751969Y114567D02*
G03X755906Y118504I0J3937D01*
G01D02*
Y183465D01*
G01X763780Y152756D02*
G03X755906I-3937J0D01*
G01Y183465D02*
G03X751969Y187402I-3937J0D01*
G01X734843Y191339D02*
G03X738780Y187402I3937J0D01*
G01X751969D02*
X738780D01*
G01X734843Y219292D02*
X732874Y221260D01*
G01X734843Y219292D02*
Y191339D01*
G01X755906Y183465D02*
G03X763780I3937J0D01*
G01Y302855D02*
Y183460D01*
G01X734843Y237008D02*
Y294981D01*
G01D02*
Y268898D01*
G01X732874Y235040D02*
X734843Y237008D01*
G01X755906Y337796D02*
G03X751969Y341733I-3937J0D01*
G01Y298918D02*
G03X755906Y302855I0J3937D01*
G01X738780Y298918D02*
G03X734843Y294981I0J-3937D01*
G01X755906Y337796D02*
Y302855D01*
G01X751969Y298918D02*
X738780D01*
G01X763780Y387796D02*
Y333559D01*
G01Y302855D02*
G03X755906I-3937J0D01*
G01Y333563D02*
G03X763780I3937J0D01*
G01X751969Y349607D02*
G03X755906Y353544I0J3937D01*
G01D02*
Y418504D01*
G01X763780Y387796D02*
G03X755906I-3937J0D01*
G01Y418504D02*
G03X751969Y422441I-3937J0D01*
G01X734843Y426378D02*
G03X738780Y422441I3937J0D01*
G01X751969D02*
X738780D01*
G01X734843Y454331D02*
X732874Y456300D01*
G01X734843Y454331D02*
Y426378D01*
G01X763780Y537894D02*
Y418504D01*
G01X755906Y418505D02*
G03X763780I3937J0D01*
G01X734843Y472048D02*
Y530020D01*
G01D02*
Y503937D01*
G01X732874Y470079D02*
X734843Y472048D01*
G01X755906Y572835D02*
G03X751969Y576772I-3937J0D01*
G01Y533957D02*
G03X755906Y537894I0J3937D01*
G01X738780Y533957D02*
G03X734843Y530020I0J-3937D01*
G01X755906Y572835D02*
Y537894D01*
G01X751969Y533957D02*
X738780D01*
G01X751969Y584646D02*
G03X755906Y588583I0J3937D01*
G01D02*
Y653544D01*
G01X775591Y561023D02*
G03Y553149I0J-3937D01*
G01X763780Y537894D02*
G03X755906I-3937J0D01*
G01Y568603D02*
G03X763780I3937J0D01*
G01X775591Y676339D02*
Y561023D01*
G01X763780Y622835D02*
Y568603D01*
G01Y622835D02*
G03X755906I-3937J0D01*
G01Y653544D02*
G03X763780I3937J0D01*
G01X755906D02*
G03X751969Y657481I-3937J0D01*
G01X734843Y661418D02*
G03X738780Y657481I3937J0D01*
G01X751969D02*
X738780D01*
G01X734843Y689371D02*
X732874Y691339D01*
G01X734843Y689371D02*
Y661418D01*
G01X760014Y677788D02*
G03I-4292J0D01*
G01X775591Y676339D02*
G03X760591Y691339I-15000J0D01*
G01X751969Y665355D02*
X742717D01*
G01X763780Y653544D02*
G03X751969Y665355I-11811J0D01*
G01X742717Y691339D02*
X760591D01*
G01X742717Y665355D02*
Y691339D01*
M02*
